# S9S_MB_2U (Grand Teton) — schematic netlist excerpt (pin names and nets, part order shuffled) for the footprints in the layout excerpt that follows; sources: Cadence DE-HDL packaged netlist, KiCad conversion of 03242023_DA0F0TMBIJ0_F0T_Motherboard_J_brd_V01_OCP.brd

PC252_P0_6  Q_CAP  3300PF 50V 10% X7R  pkg 0402  page 269 : A = SW_P12V_PVCCIN_CPU0_FLT ; B = GND
R3489  Q_RES  100K 1% EMPTY  pkg 0402LF  page 150 : A = GPU_FPGA_EROT_RST_N ; B = GND

(kicad_pcb
	(version 20260206)
	(generator "pcbnew")
	(generator_version "10.0")
	(general
		(thickness 1.6)
		(legacy_teardrops no)
	)
	(paper "A4")
	(title_block
		(title "03242023_DA0F0TMBIJ0_F0T_Motherboard_J_brd_V01_OCP.brd")
		(comment 1 "Grand Teton / footprints 4087-4088 of 6105")
	)
	(layers
		(0 "F.Cu" signal "TOP")
		(4 "In1.Cu" signal "GND")
		(6 "In2.Cu" signal "IN1")
		(8 "In3.Cu" signal "GND1")
		(10 "In4.Cu" signal "IN2")
		(12 "In5.Cu" signal "GND2")
		(14 "In6.Cu" signal "IN3")
		(16 "In7.Cu" signal "GND3")
		(18 "In8.Cu" signal "VCC")
		(20 "In9.Cu" signal "VCC1")
		(22 "In10.Cu" signal "GND4")
		(24 "In11.Cu" signal "IN4")
		(26 "In12.Cu" signal "GND5")
		(28 "In13.Cu" signal "IN5")
		(30 "In14.Cu" signal "GND6")
		(32 "In15.Cu" signal "IN6")
		(34 "In16.Cu" signal "GND7")
		(2 "B.Cu" signal "BOTTOM")
		(9 "F.Adhes" user "F.Adhesive")
		(11 "B.Adhes" user "B.Adhesive")
		(13 "F.Paste" user "Package Geometry/Pastemask Top")
		(15 "B.Paste" user "Package Geometry/Pastemask Bottom")
		(5 "F.SilkS" user "Ref Des/Silkscreen Top")
		(7 "B.SilkS" user "Ref Des/Silkscreen Bottom")
		(1 "F.Mask" user "Board Geometry/Soldermask Top")
		(3 "B.Mask" user "Board Geometry/Soldermask Bottom")
		(17 "Dwgs.User" user "User.Drawings")
		(19 "Cmts.User" user "User.Comments")
		(21 "Eco1.User" user "User.Eco1")
		(23 "Eco2.User" user "User.Eco2")
		(25 "Edge.Cuts" user "Board Geometry/Outline")
		(27 "Margin" user)
		(31 "F.CrtYd" user "Package Geometry/Place Bound Top")
		(29 "B.CrtYd" user "Package Geometry/Place Bound Bottom")
		(35 "F.Fab" user "Ref Des/Assembly Top")
		(33 "B.Fab" user "Ref Des/Assembly Bottom")
	)
	(footprint ""
		(layer "F.Cu")
		(at 109.580934 -395.17574)
		(property "Reference" "R3489"
			(at 0 0 0)
			(layer "F.SilkS")
			(hide yes)
			(effects
				(font
					(size 1.27 1.27)
				)
			)
		)
		(property "Value" ""
			(at 0 0 0)
			(layer "F.Fab")
			(effects
				(font
					(size 1.27 1.27)
				)
			)
		)
		(duplicate_pad_numbers_are_jumpers no)
		(fp_line
			(start -0.7874 -0.4064)
			(end 0.7874 -0.4064)
			(stroke
				(width 0.1524)
				(type default)
			)
			(layer "F.SilkS")
		)
		(fp_line
			(start -0.7874 0.4064)
			(end -0.7874 -0.4064)
			(stroke
				(width 0.1524)
				(type default)
			)
			(layer "F.SilkS")
		)
		(fp_line
			(start 0.7874 -0.4064)
			(end 0.7874 0.4064)
			(stroke
				(width 0.1524)
				(type default)
			)
			(layer "F.SilkS")
		)
		(fp_line
			(start 0.7874 0.4064)
			(end -0.7874 0.4064)
			(stroke
				(width 0.1524)
				(type default)
			)
			(layer "F.SilkS")
		)
		(fp_line
			(start -0.67945 -0.305054)
			(end -0.12065 -0.305054)
			(stroke
				(width 0.1)
				(type default)
			)
			(layer "F.Fab")
		)
		(fp_line
			(start -0.67945 0.3048)
			(end -0.67945 -0.305054)
			(stroke
				(width 0.1)
				(type default)
			)
			(layer "F.Fab")
		)
		(fp_line
			(start -0.12065 -0.305054)
			(end -0.12065 -0.2794)
			(stroke
				(width 0.1)
				(type default)
			)
			(layer "F.Fab")
		)
		(fp_line
			(start -0.12065 -0.2794)
			(end 0.12065 -0.2794)
			(stroke
				(width 0.1)
				(type default)
			)
			(layer "F.Fab")
		)
		(fp_line
			(start -0.12065 0.2794)
			(end -0.12065 0.3048)
			(stroke
				(width 0.1)
				(type default)
			)
			(layer "F.Fab")
		)
		(fp_line
			(start -0.12065 0.3048)
			(end -0.67945 0.3048)
			(stroke
				(width 0.1)
				(type default)
			)
			(layer "F.Fab")
		)
		(fp_line
			(start 0.120396 0.2794)
			(end -0.12065 0.2794)
			(stroke
				(width 0.1)
				(type default)
			)
			(layer "F.Fab")
		)
		(fp_line
			(start 0.120396 0.3048)
			(end 0.120396 0.2794)
			(stroke
				(width 0.1)
				(type default)
			)
			(layer "F.Fab")
		)
		(fp_line
			(start 0.12065 -0.3048)
			(end 0.67945 -0.3048)
			(stroke
				(width 0.1)
				(type default)
			)
			(layer "F.Fab")
		)
		(fp_line
			(start 0.12065 -0.2794)
			(end 0.12065 -0.3048)
			(stroke
				(width 0.1)
				(type default)
			)
			(layer "F.Fab")
		)
		(fp_line
			(start 0.67945 -0.3048)
			(end 0.67945 0.3048)
			(stroke
				(width 0.1)
				(type default)
			)
			(layer "F.Fab")
		)
		(fp_line
			(start 0.67945 0.3048)
			(end 0.120396 0.3048)
			(stroke
				(width 0.1)
				(type default)
			)
			(layer "F.Fab")
		)
		(pad "1" smd circle
			(at -0.40005 0)
			(size 0 0)
			(layers "F.Cu" "F.Mask" "F.Paste")
			(net "GPU_FPGA_EROT_RST_N")
		)
		(pad "2" smd circle
			(at 0.40005 0)
			(size 0 0)
			(layers "F.Cu" "F.Mask" "F.Paste")
			(net "GND")
		)
	)
	(footprint ""
		(layer "F.Cu")
		(at 341.133176 -339.51545 -90)
		(property "Reference" "PC252_P0_6"
			(at 0 0 270)
			(layer "F.SilkS")
			(hide yes)
			(effects
				(font
					(size 1.27 1.27)
				)
			)
		)
		(property "Value" ""
			(at 0 0 270)
			(layer "F.Fab")
			(effects
				(font
					(size 1.27 1.27)
				)
			)
		)
		(duplicate_pad_numbers_are_jumpers no)
		(fp_line
			(start -0.7874 0.4064)
			(end -0.7874 -0.4064)
			(stroke
				(width 0.1524)
				(type default)
			)
			(layer "F.SilkS")
		)
		(fp_line
			(start 0.7874 0.4064)
			(end -0.7874 0.4064)
			(stroke
				(width 0.1524)
				(type default)
			)
			(layer "F.SilkS")
		)
		(fp_line
			(start -0.7874 -0.4064)
			(end 0.7874 -0.4064)
			(stroke
				(width 0.1524)
				(type default)
			)
			(layer "F.SilkS")
		)
		(fp_line
			(start 0.7874 -0.4064)
			(end 0.7874 0.4064)
			(stroke
				(width 0.1524)
				(type default)
			)
			(layer "F.SilkS")
		)
		(fp_line
			(start -0.67945 0.3048)
			(end -0.67945 -0.305054)
			(stroke
				(width 0.1)
				(type default)
			)
			(layer "F.Fab")
		)
		(fp_line
			(start -0.12065 0.3048)
			(end -0.67945 0.3048)
			(stroke
				(width 0.1)
				(type default)
			)
			(layer "F.Fab")
		)
		(fp_line
			(start 0.120396 0.3048)
			(end 0.120396 0.2794)
			(stroke
				(width 0.1)
				(type default)
			)
			(layer "F.Fab")
		)
		(fp_line
			(start 0.67945 0.3048)
			(end 0.120396 0.3048)
			(stroke
				(width 0.1)
				(type default)
			)
			(layer "F.Fab")
		)
		(fp_line
			(start -0.12065 0.2794)
			(end -0.12065 0.3048)
			(stroke
				(width 0.1)
				(type default)
			)
			(layer "F.Fab")
		)
		(fp_line
			(start 0.120396 0.2794)
			(end -0.12065 0.2794)
			(stroke
				(width 0.1)
				(type default)
			)
			(layer "F.Fab")
		)
		(fp_line
			(start -0.12065 -0.2794)
			(end 0.12065 -0.2794)
			(stroke
				(width 0.1)
				(type default)
			)
			(layer "F.Fab")
		)
		(fp_line
			(start 0.12065 -0.2794)
			(end 0.12065 -0.3048)
			(stroke
				(width 0.1)
				(type default)
			)
			(layer "F.Fab")
		)
		(fp_line
			(start 0.12065 -0.3048)
			(end 0.67945 -0.3048)
			(stroke
				(width 0.1)
				(type default)
			)
			(layer "F.Fab")
		)
		(fp_line
			(start 0.67945 -0.3048)
			(end 0.67945 0.3048)
			(stroke
				(width 0.1)
				(type default)
			)
			(layer "F.Fab")
		)
		(fp_line
			(start -0.67945 -0.305054)
			(end -0.12065 -0.305054)
			(stroke
				(width 0.1)
				(type default)
			)
			(layer "F.Fab")
		)
		(fp_line
			(start -0.12065 -0.305054)
			(end -0.12065 -0.2794)
			(stroke
				(width 0.1)
				(type default)
			)
			(layer "F.Fab")
		)
		(pad "1" smd circle
			(at -0.40005 0 270)
			(size 0 0)
			(layers "F.Cu" "F.Mask" "F.Paste")
			(net "SW_P12V_PVCCIN_CPU0_FLT")
		)
		(pad "2" smd circle
			(at 0.40005 0 270)
			(size 0 0)
			(layers "F.Cu" "F.Mask" "F.Paste")
			(net "GND")
		)
	)
)
